# S9S_MB_2U (Grand Teton) — schematic netlist excerpt (pin names and nets, part order shuffled) for the footprints in the layout excerpt that follows; sources: Cadence DE-HDL packaged netlist, KiCad conversion of 03242023_DA0F0TMBIJ0_F0T_Motherboard_J_brd_V01_OCP.brd

C533  Q_CAP  47UF 2.5V 20% X6S  pkg C0603  page 75 : A = PVCCINFAON_CPU0 ; B = GND
PC266_P0_6  Q_CAP  22UF 4V 20% X6S  pkg C0805  page 269 : A = PVCCIN_CPU0 ; B = GND
R3175  Q_RES  10K 1% CHIP  pkg 0402LF  page 159 : A = SGPIO_OCP_V3_2_DATAOUT ; B = GND

(kicad_pcb
	(version 20260206)
	(generator "pcbnew")
	(generator_version "10.0")
	(general
		(thickness 1.6)
		(legacy_teardrops no)
	)
	(paper "A4")
	(title_block
		(title "03242023_DA0F0TMBIJ0_F0T_Motherboard_J_brd_V01_OCP.brd")
		(comment 1 "Grand Teton / footprints 5665-5667 of 6105")
	)
	(layers
		(0 "F.Cu" signal "TOP")
		(4 "In1.Cu" signal "GND")
		(6 "In2.Cu" signal "IN1")
		(8 "In3.Cu" signal "GND1")
		(10 "In4.Cu" signal "IN2")
		(12 "In5.Cu" signal "GND2")
		(14 "In6.Cu" signal "IN3")
		(16 "In7.Cu" signal "GND3")
		(18 "In8.Cu" signal "VCC")
		(20 "In9.Cu" signal "VCC1")
		(22 "In10.Cu" signal "GND4")
		(24 "In11.Cu" signal "IN4")
		(26 "In12.Cu" signal "GND5")
		(28 "In13.Cu" signal "IN5")
		(30 "In14.Cu" signal "GND6")
		(32 "In15.Cu" signal "IN6")
		(34 "In16.Cu" signal "GND7")
		(2 "B.Cu" signal "BOTTOM")
		(9 "F.Adhes" user "F.Adhesive")
		(11 "B.Adhes" user "B.Adhesive")
		(13 "F.Paste" user "Package Geometry/Pastemask Top")
		(15 "B.Paste" user "Package Geometry/Pastemask Bottom")
		(5 "F.SilkS" user "Ref Des/Silkscreen Top")
		(7 "B.SilkS" user "Ref Des/Silkscreen Bottom")
		(1 "F.Mask" user "Board Geometry/Soldermask Top")
		(3 "B.Mask" user "Board Geometry/Soldermask Bottom")
		(17 "Dwgs.User" user "User.Drawings")
		(19 "Cmts.User" user "User.Comments")
		(21 "Eco1.User" user "User.Eco1")
		(23 "Eco2.User" user "User.Eco2")
		(25 "Edge.Cuts" user "Board Geometry/Outline")
		(27 "Margin" user)
		(31 "F.CrtYd" user "Package Geometry/Place Bound Top")
		(29 "B.CrtYd" user "Package Geometry/Place Bound Bottom")
		(35 "F.Fab" user "Ref Des/Assembly Top")
		(33 "B.Fab" user "Ref Des/Assembly Bottom")
	)
	(footprint ""
		(layer "B.Cu")
		(at 365.816134 -237.709202 -90)
		(property "Reference" "C533"
			(at 0 0 90)
			(layer "B.SilkS")
			(hide yes)
			(effects
				(font
					(size 1.27 1.27)
				)
				(justify mirror)
			)
		)
		(property "Value" ""
			(at 0 0 90)
			(layer "B.Fab")
			(effects
				(font
					(size 1.27 1.27)
				)
				(justify mirror)
			)
		)
		(duplicate_pad_numbers_are_jumpers no)
		(fp_line
			(start -1.2954 0.5842)
			(end 1.2954 0.5842)
			(stroke
				(width 0.1524)
				(type default)
			)
			(layer "B.SilkS")
		)
		(fp_line
			(start 1.2954 0.5842)
			(end 1.2954 -0.5842)
			(stroke
				(width 0.1524)
				(type default)
			)
			(layer "B.SilkS")
		)
		(fp_line
			(start -1.2954 -0.5842)
			(end -1.2954 0.5842)
			(stroke
				(width 0.1524)
				(type default)
			)
			(layer "B.SilkS")
		)
		(fp_line
			(start 0 -0.5842)
			(end 0 0.5842)
			(stroke
				(width 0.1524)
				(type default)
			)
			(layer "B.SilkS")
		)
		(fp_line
			(start 1.2954 -0.5842)
			(end -1.2954 -0.5842)
			(stroke
				(width 0.1524)
				(type default)
			)
			(layer "B.SilkS")
		)
		(fp_line
			(start -0.8636 0.4572)
			(end 0.8636 0.4572)
			(stroke
				(width 0.1)
				(type default)
			)
			(layer "B.Fab")
		)
		(fp_line
			(start 0.8636 0.4572)
			(end 0.8636 0.4064)
			(stroke
				(width 0.1)
				(type default)
			)
			(layer "B.Fab")
		)
		(fp_line
			(start -1.1938 0.4064)
			(end -0.8636 0.4064)
			(stroke
				(width 0.1)
				(type default)
			)
			(layer "B.Fab")
		)
		(fp_line
			(start -0.8636 0.4064)
			(end -0.8636 0.4572)
			(stroke
				(width 0.1)
				(type default)
			)
			(layer "B.Fab")
		)
		(fp_line
			(start 0.8636 0.4064)
			(end 1.1938 0.4064)
			(stroke
				(width 0.1)
				(type default)
			)
			(layer "B.Fab")
		)
		(fp_line
			(start 1.1938 0.4064)
			(end 1.1938 -0.4064)
			(stroke
				(width 0.1)
				(type default)
			)
			(layer "B.Fab")
		)
		(fp_line
			(start -1.1938 -0.4064)
			(end -1.1938 0.4064)
			(stroke
				(width 0.1)
				(type default)
			)
			(layer "B.Fab")
		)
		(fp_line
			(start -0.8636 -0.4064)
			(end -1.1938 -0.4064)
			(stroke
				(width 0.1)
				(type default)
			)
			(layer "B.Fab")
		)
		(fp_line
			(start 0.8636 -0.4064)
			(end 0.8636 -0.4572)
			(stroke
				(width 0.1)
				(type default)
			)
			(layer "B.Fab")
		)
		(fp_line
			(start 1.1938 -0.4064)
			(end 0.8636 -0.4064)
			(stroke
				(width 0.1)
				(type default)
			)
			(layer "B.Fab")
		)
		(fp_line
			(start -0.8636 -0.4572)
			(end -0.8636 -0.4064)
			(stroke
				(width 0.1)
				(type default)
			)
			(layer "B.Fab")
		)
		(fp_line
			(start 0.8636 -0.4572)
			(end -0.8636 -0.4572)
			(stroke
				(width 0.1)
				(type default)
			)
			(layer "B.Fab")
		)
		(pad "1" smd rect
			(at 0.7366 0 180)
			(size 0.7112 0.8128)
			(layers "B.Cu" "B.Mask" "B.Paste")
			(net "PVCCINFAON_CPU0")
		)
		(pad "2" smd rect
			(at -0.7366 0 180)
			(size 0.7112 0.8128)
			(layers "B.Cu" "B.Mask" "B.Paste")
			(net "GND")
		)
	)
	(footprint ""
		(layer "B.Cu")
		(at 340.374986 -328.298048 -90)
		(property "Reference" "PC266_P0_6"
			(at 0 0 90)
			(layer "B.SilkS")
			(hide yes)
			(effects
				(font
					(size 1.27 1.27)
				)
				(justify mirror)
			)
		)
		(property "Value" ""
			(at 0 0 90)
			(layer "B.Fab")
			(effects
				(font
					(size 1.27 1.27)
				)
				(justify mirror)
			)
		)
		(duplicate_pad_numbers_are_jumpers no)
		(fp_line
			(start -1.524 0.762)
			(end 1.524 0.762)
			(stroke
				(width 0.1524)
				(type default)
			)
			(layer "B.SilkS")
		)
		(fp_line
			(start 1.524 0.762)
			(end 1.524 -0.762)
			(stroke
				(width 0.1524)
				(type default)
			)
			(layer "B.SilkS")
		)
		(fp_line
			(start -1.524 -0.762)
			(end -1.524 0.762)
			(stroke
				(width 0.1524)
				(type default)
			)
			(layer "B.SilkS")
		)
		(fp_line
			(start 1.524 -0.762)
			(end -1.524 -0.762)
			(stroke
				(width 0.1524)
				(type default)
			)
			(layer "B.SilkS")
		)
		(fp_line
			(start -1.1049 0.724916)
			(end -1.1049 -0.724916)
			(stroke
				(width 0.1)
				(type default)
			)
			(layer "B.Fab")
		)
		(fp_line
			(start 1.1049 0.724916)
			(end -1.1049 0.724916)
			(stroke
				(width 0.1)
				(type default)
			)
			(layer "B.Fab")
		)
		(fp_line
			(start -1.1049 -0.724916)
			(end 1.1049 -0.724916)
			(stroke
				(width 0.1)
				(type default)
			)
			(layer "B.Fab")
		)
		(fp_line
			(start 1.1049 -0.724916)
			(end 1.1049 0.724916)
			(stroke
				(width 0.1)
				(type default)
			)
			(layer "B.Fab")
		)
		(pad "1" smd rect
			(at 0.889 0 270)
			(size 1.016 1.27)
			(layers "B.Cu" "B.Mask" "B.Paste")
			(net "PVCCIN_CPU0")
		)
		(pad "2" smd rect
			(at -0.889 0 270)
			(size 1.016 1.27)
			(layers "B.Cu" "B.Mask" "B.Paste")
			(net "GND")
		)
	)
	(footprint ""
		(layer "B.Cu")
		(at 157.02788 -118.836948)
		(property "Reference" "R3175"
			(at 0 0 0)
			(layer "B.SilkS")
			(hide yes)
			(effects
				(font
					(size 1.27 1.27)
				)
				(justify mirror)
			)
		)
		(property "Value" ""
			(at 0 0 0)
			(layer "B.Fab")
			(effects
				(font
					(size 1.27 1.27)
				)
				(justify mirror)
			)
		)
		(duplicate_pad_numbers_are_jumpers no)
		(fp_line
			(start -0.7874 -0.4064)
			(end -0.7874 0.4064)
			(stroke
				(width 0.1524)
				(type default)
			)
			(layer "B.SilkS")
		)
		(fp_line
			(start -0.7874 0.4064)
			(end 0.7874 0.4064)
			(stroke
				(width 0.1524)
				(type default)
			)
			(layer "B.SilkS")
		)
		(fp_line
			(start 0.7874 -0.4064)
			(end -0.7874 -0.4064)
			(stroke
				(width 0.1524)
				(type default)
			)
			(layer "B.SilkS")
		)
		(fp_line
			(start 0.7874 0.4064)
			(end 0.7874 -0.4064)
			(stroke
				(width 0.1524)
				(type default)
			)
			(layer "B.SilkS")
		)
		(fp_line
			(start -0.67945 -0.3048)
			(end -0.67945 0.3048)
			(stroke
				(width 0.1)
				(type default)
			)
			(layer "B.Fab")
		)
		(fp_line
			(start -0.67945 0.3048)
			(end -0.120396 0.3048)
			(stroke
				(width 0.1)
				(type default)
			)
			(layer "B.Fab")
		)
		(fp_line
			(start -0.12065 -0.3048)
			(end -0.67945 -0.3048)
			(stroke
				(width 0.1)
				(type default)
			)
			(layer "B.Fab")
		)
		(fp_line
			(start -0.12065 -0.2794)
			(end -0.12065 -0.3048)
			(stroke
				(width 0.1)
				(type default)
			)
			(layer "B.Fab")
		)
		(fp_line
			(start -0.120396 0.2794)
			(end 0.12065 0.2794)
			(stroke
				(width 0.1)
				(type default)
			)
			(layer "B.Fab")
		)
		(fp_line
			(start -0.120396 0.3048)
			(end -0.120396 0.2794)
			(stroke
				(width 0.1)
				(type default)
			)
			(layer "B.Fab")
		)
		(fp_line
			(start 0.12065 -0.305054)
			(end 0.12065 -0.2794)
			(stroke
				(width 0.1)
				(type default)
			)
			(layer "B.Fab")
		)
		(fp_line
			(start 0.12065 -0.2794)
			(end -0.12065 -0.2794)
			(stroke
				(width 0.1)
				(type default)
			)
			(layer "B.Fab")
		)
		(fp_line
			(start 0.12065 0.2794)
			(end 0.12065 0.3048)
			(stroke
				(width 0.1)
				(type default)
			)
			(layer "B.Fab")
		)
		(fp_line
			(start 0.12065 0.3048)
			(end 0.67945 0.3048)
			(stroke
				(width 0.1)
				(type default)
			)
			(layer "B.Fab")
		)
		(fp_line
			(start 0.67945 -0.305054)
			(end 0.12065 -0.305054)
			(stroke
				(width 0.1)
				(type default)
			)
			(layer "B.Fab")
		)
		(fp_line
			(start 0.67945 0.3048)
			(end 0.67945 -0.305054)
			(stroke
				(width 0.1)
				(type default)
			)
			(layer "B.Fab")
		)
		(pad "1" smd circle
			(at 0.40005 0 180)
			(size 0 0)
			(layers "B.Cu" "B.Mask" "B.Paste")
			(net "SGPIO_OCP_V3_2_DATAOUT")
		)
		(pad "2" smd circle
			(at -0.40005 0 180)
			(size 0 0)
			(layers "B.Cu" "B.Mask" "B.Paste")
			(net "GND")
		)
	)
)
